# BASEBOARD_FAB2 (Tioga Pass) — schematic netlist excerpt (pin names and nets, part order shuffled) for the footprints in the layout excerpt that follows; sources: Cadence DE-HDL packaged netlist, KiCad conversion of Wiwynn_Tioga_Pass_MB.brd

C2T37  CAP_A  0.01UF 25V 10% X7R  pkg 0402V  page 101 : A = P3V3_STBY_MNG_RMII ; B = GND
R9R10  RES  0.0 5% CHIP  pkg 0402  page 181 : A = FAN_TACH1 ; B = FAN_TACH1_R
SH4U1  SHUNT  EMPTY  pkg SH0201  page 217 : A = VSENSE_PVDDQ_ABC_N ; B = GND

(kicad_pcb
	(version 20260206)
	(generator "pcbnew")
	(generator_version "10.0")
	(general
		(thickness 1.6)
		(legacy_teardrops no)
	)
	(paper "A4")
	(title_block
		(title "Wiwynn_Tioga_Pass_MB.brd")
		(comment 1 "Tioga Pass / footprints 4709-4711 of 4770")
	)
	(layers
		(0 "F.Cu" signal "TOP")
		(4 "In1.Cu" signal "L2GND")
		(6 "In2.Cu" signal "L3")
		(8 "In3.Cu" signal "L4GND")
		(10 "In4.Cu" signal "L5")
		(12 "In5.Cu" signal "L6GND")
		(14 "In6.Cu" signal "L7VCC")
		(16 "In7.Cu" signal "L8VCC")
		(18 "In8.Cu" signal "L9GND")
		(20 "In9.Cu" signal "L10")
		(22 "In10.Cu" signal "L11GND")
		(24 "In11.Cu" signal "L12")
		(26 "In12.Cu" signal "L13GND")
		(2 "B.Cu" signal "BOTTOM")
		(9 "F.Adhes" user "F.Adhesive")
		(11 "B.Adhes" user "B.Adhesive")
		(13 "F.Paste" user "Package Geometry/Pastemask Top")
		(15 "B.Paste" user "Package Geometry/Pastemask Bottom")
		(5 "F.SilkS" user "Ref Des/Silkscreen Top")
		(7 "B.SilkS" user "Ref Des/Silkscreen Bottom")
		(1 "F.Mask" user "Board Geometry/Soldermask Top")
		(3 "B.Mask" user "Board Geometry/Soldermask Bottom")
		(17 "Dwgs.User" user "User.Drawings")
		(19 "Cmts.User" user "User.Comments")
		(21 "Eco1.User" user "User.Eco1")
		(23 "Eco2.User" user "User.Eco2")
		(25 "Edge.Cuts" user "Board Geometry/Outline")
		(27 "Margin" user)
		(31 "F.CrtYd" user "Package Geometry/Place Bound Top")
		(29 "B.CrtYd" user "Package Geometry/Place Bound Bottom")
		(35 "F.Fab" user "Ref Des/Assembly Top")
		(33 "B.Fab" user "Ref Des/Assembly Bottom")
	)
	(footprint ""
		(layer "B.Cu")
		(at 278.7142 -29.337 90)
		(property "Reference" "SH4U1"
			(at 0 0 90)
			(layer "B.SilkS")
			(hide yes)
			(effects
				(font
					(size 1.27 1.27)
				)
				(justify mirror)
			)
		)
		(property "Value" ""
			(at 0 0 90)
			(layer "B.Fab")
			(effects
				(font
					(size 1.27 1.27)
				)
				(justify mirror)
			)
		)
		(duplicate_pad_numbers_are_jumpers no)
		(fp_poly
			(pts
				(xy 0.1651 -0.0508) (xy 0.1651 0.5842) (xy -0.1651 0.5842) (xy -0.1651 -0.0508)
			)
			(stroke
				(width 0)
				(type default)
			)
			(fill no)
			(layer "B.CrtYd")
		)
		(fp_line
			(start 0.1651 -0.0508)
			(end -0.1651 -0.0508)
			(stroke
				(width 0.1)
				(type default)
			)
			(layer "B.Fab")
		)
		(fp_line
			(start -0.1651 -0.0508)
			(end -0.1651 0.5842)
			(stroke
				(width 0.1)
				(type default)
			)
			(layer "B.Fab")
		)
		(fp_line
			(start 0.1651 0.5842)
			(end 0.1651 -0.0508)
			(stroke
				(width 0.1)
				(type default)
			)
			(layer "B.Fab")
		)
		(fp_line
			(start -0.1651 0.5842)
			(end 0.1651 0.5842)
			(stroke
				(width 0.1)
				(type default)
			)
			(layer "B.Fab")
		)
		(pad "1" smd custom
			(at 0 0 90)
			(size 0.0762 0.0762)
			(layers "B.Cu" "B.Mask" "B.Paste")
			(net "VSENSE_PVDDQ_ABC_N")
			(options
				(clearance outline)
				(anchor circle)
			)
			(primitives
				(gr_poly
					(pts
						(arc
							(start -0.1524 0.10795)
							(mid -0.098518 0.130268)
							(end -0.0762 0.18415)
						)
						(xy -0.0762 0.22225) (xy 0.0762 0.22225)
						(arc
							(start 0.0762 0.18415)
							(mid 0.098518 0.130268)
							(end 0.1524 0.10795)
						)
						(xy 0.1524 -0.22225) (xy -0.1524 -0.22225)
					)
					(width 0)
					(fill yes)
				)
			)
		)
		(pad "2" smd custom
			(at 0 0.5334 270)
			(size 0.0762 0.0762)
			(layers "B.Cu" "B.Mask" "B.Paste")
			(net "GND")
			(options
				(clearance outline)
				(anchor circle)
			)
			(primitives
				(gr_poly
					(pts
						(arc
							(start -0.1524 0.10795)
							(mid -0.098518 0.130268)
							(end -0.0762 0.18415)
						)
						(xy -0.0762 0.22225) (xy 0.0762 0.22225)
						(arc
							(start 0.0762 0.18415)
							(mid 0.098518 0.130268)
							(end 0.1524 0.10795)
						)
						(xy 0.1524 -0.22225) (xy -0.1524 -0.22225)
					)
					(width 0)
					(fill yes)
				)
			)
		)
	)
	(footprint ""
		(layer "B.Cu")
		(at 13.97 -41.402 -90)
		(property "Reference" "R9R10"
			(at 0 0 90)
			(layer "B.SilkS")
			(hide yes)
			(effects
				(font
					(size 1.27 1.27)
				)
				(justify mirror)
			)
		)
		(property "Value" ""
			(at 0 0 90)
			(layer "B.Fab")
			(effects
				(font
					(size 1.27 1.27)
				)
				(justify mirror)
			)
		)
		(duplicate_pad_numbers_are_jumpers no)
		(fp_poly
			(pts
				(xy 0.2794 -0.1016) (xy -0.2794 -0.1016) (xy -0.2794 0.9906) (xy 0.2794 0.9906)
			)
			(stroke
				(width 0)
				(type default)
			)
			(fill no)
			(layer "B.CrtYd")
		)
		(fp_line
			(start -0.2794 0.9906)
			(end -0.2794 -0.1016)
			(stroke
				(width 0.1)
				(type default)
			)
			(layer "B.Fab")
		)
		(fp_line
			(start 0.2794 0.9906)
			(end -0.2794 0.9906)
			(stroke
				(width 0.1)
				(type default)
			)
			(layer "B.Fab")
		)
		(fp_line
			(start -0.2794 -0.1016)
			(end 0.2794 -0.1016)
			(stroke
				(width 0.1)
				(type default)
			)
			(layer "B.Fab")
		)
		(fp_line
			(start 0.2794 -0.1016)
			(end 0.2794 0.9906)
			(stroke
				(width 0.1)
				(type default)
			)
			(layer "B.Fab")
		)
		(pad "1" smd rect
			(at 0 0 90)
			(size 0.508 0.508)
			(layers "B.Cu" "B.Mask" "B.Paste")
			(net "FAN_TACH1")
		)
		(pad "2" smd rect
			(at 0 0.889 90)
			(size 0.508 0.508)
			(layers "B.Cu" "B.Mask" "B.Paste")
			(net "FAN_TACH1_R")
		)
		(zone
			(layer "B.Cu")
			(hatch none 0.5)
			(connect_pads
				(clearance 0)
			)
			(min_thickness 0.25)
			(keepout
				(tracks not_allowed)
				(vias allowed)
				(pads allowed)
				(copperpour not_allowed)
				(footprints allowed)
			)
			(placement
				(enabled no)
				(sheetname "")
			)
			(fill
				(thermal_gap 0.5)
				(thermal_bridge_width 0.5)
				(island_removal_mode 0)
			)
			(polygon
				(pts
					(xy 13.335 -41.148) (xy 13.335 -41.656) (xy 13.716 -41.656) (xy 13.716 -41.148)
				)
			)
		)
		(zone
			(layer "B.Cu")
			(hatch none 0.5)
			(connect_pads
				(clearance 0)
			)
			(min_thickness 0.25)
			(keepout
				(tracks allowed)
				(vias not_allowed)
				(pads allowed)
				(copperpour not_allowed)
				(footprints allowed)
			)
			(placement
				(enabled no)
				(sheetname "")
			)
			(fill
				(thermal_gap 0.5)
				(thermal_bridge_width 0.5)
				(island_removal_mode 0)
			)
			(polygon
				(pts
					(xy 13.716 -41.148) (xy 13.716 -41.656) (xy 13.335 -41.656) (xy 13.335 -41.148)
				)
			)
		)
	)
	(footprint ""
		(layer "B.Cu")
		(at 477.774 -34.0995)
		(property "Reference" "C2T37"
			(at 0 0 0)
			(layer "B.SilkS")
			(hide yes)
			(effects
				(font
					(size 1.27 1.27)
				)
				(justify mirror)
			)
		)
		(property "Value" ""
			(at 0 0 0)
			(layer "B.Fab")
			(effects
				(font
					(size 1.27 1.27)
				)
				(justify mirror)
			)
		)
		(duplicate_pad_numbers_are_jumpers no)
		(fp_poly
			(pts
				(xy -0.3048 -0.1016) (xy -0.3048 0.9906) (xy 0.3048 0.9906) (xy 0.3048 -0.1016)
			)
			(stroke
				(width 0)
				(type default)
			)
			(fill no)
			(layer "B.CrtYd")
		)
		(fp_line
			(start -0.3048 -0.1016)
			(end 0.3048 -0.1016)
			(stroke
				(width 0.1)
				(type default)
			)
			(layer "B.Fab")
		)
		(fp_line
			(start -0.3048 0.9906)
			(end -0.3048 -0.1016)
			(stroke
				(width 0.1)
				(type default)
			)
			(layer "B.Fab")
		)
		(fp_line
			(start 0.3048 -0.1016)
			(end 0.3048 0.9906)
			(stroke
				(width 0.1)
				(type default)
			)
			(layer "B.Fab")
		)
		(fp_line
			(start 0.3048 0.9906)
			(end -0.3048 0.9906)
			(stroke
				(width 0.1)
				(type default)
			)
			(layer "B.Fab")
		)
		(pad "1" smd rect
			(at 0 0 180)
			(size 0.508 0.508)
			(layers "B.Cu" "B.Mask" "B.Paste")
			(net "P3V3_STBY_MNG_RMII")
		)
		(pad "2" smd rect
			(at 0 0.889 180)
			(size 0.508 0.508)
			(layers "B.Cu" "B.Mask" "B.Paste")
			(net "GND")
		)
		(zone
			(layer "B.Cu")
			(hatch none 0.5)
			(connect_pads
				(clearance 0)
			)
			(min_thickness 0.25)
			(keepout
				(tracks allowed)
				(vias not_allowed)
				(pads allowed)
				(copperpour not_allowed)
				(footprints allowed)
			)
			(placement
				(enabled no)
				(sheetname "")
			)
			(fill
				(thermal_gap 0.5)
				(thermal_bridge_width 0.5)
				(island_removal_mode 0)
			)
			(polygon
				(pts
					(xy 478.028 -33.8455) (xy 477.52 -33.8455) (xy 477.52 -33.4645) (xy 478.028 -33.4645)
				)
			)
		)
		(zone
			(layer "B.Cu")
			(hatch none 0.5)
			(connect_pads
				(clearance 0)
			)
			(min_thickness 0.25)
			(keepout
				(tracks not_allowed)
				(vias allowed)
				(pads allowed)
				(copperpour not_allowed)
				(footprints allowed)
			)
			(placement
				(enabled no)
				(sheetname "")
			)
			(fill
				(thermal_gap 0.5)
				(thermal_bridge_width 0.5)
				(island_removal_mode 0)
			)
			(polygon
				(pts
					(xy 478.028 -33.4645) (xy 477.52 -33.4645) (xy 477.52 -33.8455) (xy 478.028 -33.8455)
				)
			)
		)
	)
)
